(kicad_pcb
	(version 20260206)
	(generator "pcbnew")
	(generator_version "10.0")
	(general
		(thickness 1.6)
		(legacy_teardrops no)
	)
	(paper "A4")
	(title_block
		(title "01162023_DA0F0TEBIF0_F0T_Expander_BD_F_brd_V02_OCP.brd")
		(comment 1 "Grand Teton / footprint 4451 of 9728 (PEX3), pads 356-474 of 2397")
	)
	(layers
		(0 "F.Cu" signal "TOP")
		(4 "In1.Cu" signal "GND")
		(6 "In2.Cu" signal "VCC")
		(8 "In3.Cu" signal "VCC1")
		(10 "In4.Cu" signal "GND1")
		(12 "In5.Cu" signal "IN1")
		(14 "In6.Cu" signal "GND2")
		(16 "In7.Cu" signal "IN2")
		(18 "In8.Cu" signal "GND3")
		(20 "In9.Cu" signal "IN3")
		(22 "In10.Cu" signal "GND4")
		(24 "In11.Cu" signal "IN4")
		(26 "In12.Cu" signal "GND5")
		(28 "In13.Cu" signal "IN5")
		(30 "In14.Cu" signal "GND6")
		(32 "In15.Cu" signal "IN6")
		(34 "In16.Cu" signal "GND7")
		(2 "B.Cu" signal "BOTTOM")
		(9 "F.Adhes" user "F.Adhesive")
		(11 "B.Adhes" user "B.Adhesive")
		(13 "F.Paste" user "Package Geometry/Pastemask Top")
		(15 "B.Paste" user "Package Geometry/Pastemask Bottom")
		(5 "F.SilkS" user "Ref Des/Silkscreen Top")
		(7 "B.SilkS" user "Ref Des/Silkscreen Bottom")
		(1 "F.Mask" user "Board Geometry/Soldermask Top")
		(3 "B.Mask" user "Board Geometry/Soldermask Bottom")
		(17 "Dwgs.User" user "User.Drawings")
		(19 "Cmts.User" user "User.Comments")
		(21 "Eco1.User" user "User.Eco1")
		(23 "Eco2.User" user "User.Eco2")
		(25 "Edge.Cuts" user "Board Geometry/Outline")
		(27 "Margin" user)
		(31 "F.CrtYd" user "Package Geometry/Place Bound Top")
		(29 "B.CrtYd" user "Package Geometry/Place Bound Bottom")
		(35 "F.Fab" user "Ref Des/Assembly Top")
		(33 "B.Fab" user "Ref Des/Assembly Bottom")
	)
	(footprint ""
		(layer "F.Cu")
		(at 407.949908 -295.89984)
		(property "Reference" "PEX3"
			(at -3.358642 35.5727 0)
			(unlocked yes)
			(layer "F.SilkS")
			(effects
				(font
					(size 2.032 1.524)
					(thickness 0.1524)
				)
				(justify left)
			)
		)
		(property "Value" ""
			(at 0 0 0)
			(layer "F.Fab")
			(effects
				(font
					(size 1.27 1.27)
				)
			)
		)
		(duplicate_pad_numbers_are_jumpers no)
		(pad "AG15" smd circle
			(at -9.500108 1.89992)
			(size 0.4572 0.4572)
			(layers "F.Cu" "F.Mask" "F.Paste")
			(net "P0V8_PEX3")
		)
		(pad "AG16" smd circle
			(at -8.549894 1.89992)
			(size 0.4572 0.4572)
			(layers "F.Cu" "F.Mask" "F.Paste")
			(net "GND")
		)
		(pad "AG17" smd circle
			(at -7.599934 1.89992)
			(size 0.4572 0.4572)
			(layers "F.Cu" "F.Mask" "F.Paste")
			(net "P0V8_PEX3")
		)
		(pad "AG18" smd circle
			(at -6.649974 1.89992)
			(size 0.4572 0.4572)
			(layers "F.Cu" "F.Mask" "F.Paste")
			(net "GND")
		)
		(pad "AG19" smd circle
			(at -5.700014 1.89992)
			(size 0.4572 0.4572)
			(layers "F.Cu" "F.Mask" "F.Paste")
			(net "P0V8_PEX3")
		)
		(pad "AG20" smd circle
			(at -4.750054 1.89992)
			(size 0.4572 0.4572)
			(layers "F.Cu" "F.Mask" "F.Paste")
			(net "GND")
		)
		(pad "AG21" smd circle
			(at -3.800094 1.89992)
			(size 0.4572 0.4572)
			(layers "F.Cu" "F.Mask" "F.Paste")
			(net "P0V8_PEX3")
		)
		(pad "AG22" smd circle
			(at -2.84988 1.89992)
			(size 0.4572 0.4572)
			(layers "F.Cu" "F.Mask" "F.Paste")
			(net "GND")
		)
		(pad "AG23" smd circle
			(at -1.89992 1.89992)
			(size 0.4572 0.4572)
			(layers "F.Cu" "F.Mask" "F.Paste")
			(net "P0V8_PEX3")
		)
		(pad "AG24" smd circle
			(at -0.94996 1.89992)
			(size 0.4572 0.4572)
			(layers "F.Cu" "F.Mask" "F.Paste")
			(net "GND")
		)
		(pad "AG25" smd circle
			(at 0 1.89992)
			(size 0.4572 0.4572)
			(layers "F.Cu" "F.Mask" "F.Paste")
			(net "P0V8_PEX3")
		)
		(pad "AG26" smd circle
			(at 0.94996 1.89992)
			(size 0.4572 0.4572)
			(layers "F.Cu" "F.Mask" "F.Paste")
			(net "GND")
		)
		(pad "AG27" smd circle
			(at 1.89992 1.89992)
			(size 0.4572 0.4572)
			(layers "F.Cu" "F.Mask" "F.Paste")
			(net "P0V8_PEX3")
		)
		(pad "AG28" smd circle
			(at 2.84988 1.89992)
			(size 0.4572 0.4572)
			(layers "F.Cu" "F.Mask" "F.Paste")
			(net "GND")
		)
		(pad "AG29" smd circle
			(at 3.800094 1.89992)
			(size 0.4572 0.4572)
			(layers "F.Cu" "F.Mask" "F.Paste")
			(net "P0V8_PEX3")
		)
		(pad "AG30" smd circle
			(at 4.750054 1.89992)
			(size 0.4572 0.4572)
			(layers "F.Cu" "F.Mask" "F.Paste")
			(net "GND")
		)
		(pad "AG31" smd circle
			(at 5.700014 1.89992)
			(size 0.4572 0.4572)
			(layers "F.Cu" "F.Mask" "F.Paste")
			(net "P0V8_PEX3")
		)
		(pad "AG32" smd circle
			(at 6.649974 1.89992)
			(size 0.4572 0.4572)
			(layers "F.Cu" "F.Mask" "F.Paste")
			(net "GND")
		)
		(pad "AG33" smd circle
			(at 7.599934 1.89992)
			(size 0.4572 0.4572)
			(layers "F.Cu" "F.Mask" "F.Paste")
			(net "P0V8_PEX3")
		)
		(pad "AG34" smd circle
			(at 8.549894 1.89992)
			(size 0.4572 0.4572)
			(layers "F.Cu" "F.Mask" "F.Paste")
			(net "GND")
		)
		(pad "AG35" smd circle
			(at 9.500108 1.89992)
			(size 0.4572 0.4572)
			(layers "F.Cu" "F.Mask" "F.Paste")
			(net "GND")
		)
		(pad "AG36" smd circle
			(at 10.450068 1.89992)
			(size 0.4572 0.4572)
			(layers "F.Cu" "F.Mask" "F.Paste")
			(net "P1V25_PEX3")
		)
		(pad "AG37" smd circle
			(at 11.400028 1.89992)
			(size 0.4572 0.4572)
			(layers "F.Cu" "F.Mask" "F.Paste")
			(net "GND")
		)
		(pad "AG38" smd circle
			(at 12.349988 1.89992)
			(size 0.4572 0.4572)
			(layers "F.Cu" "F.Mask" "F.Paste")
			(net "P1V25_SERDES_VDDPLL_PEX3")
		)
		(pad "AG39" smd circle
			(at 13.299948 1.89992)
			(size 0.4572 0.4572)
			(layers "F.Cu" "F.Mask" "F.Paste")
			(net "GND")
		)
		(pad "AG40" smd circle
			(at 14.249908 1.89992)
			(size 0.4572 0.4572)
			(layers "F.Cu" "F.Mask" "F.Paste")
			(net "GND")
		)
		(pad "AG41" smd circle
			(at 15.200122 1.89992)
			(size 0.4572 0.4572)
			(layers "F.Cu" "F.Mask" "F.Paste")
			(net "GND")
		)
		(pad "AG42" smd circle
			(at 16.150082 1.89992)
			(size 0.4572 0.4572)
			(layers "F.Cu" "F.Mask" "F.Paste")
			(net "GND")
		)
		(pad "AG43" smd circle
			(at 17.100042 1.89992)
			(size 0.4572 0.4572)
			(layers "F.Cu" "F.Mask" "F.Paste")
			(net "Net_1535")
		)
		(pad "AG44" smd circle
			(at 18.050002 1.89992)
			(size 0.4572 0.4572)
			(layers "F.Cu" "F.Mask" "F.Paste")
			(net "Net_1554")
		)
		(pad "AG45" smd circle
			(at 18.999962 1.89992)
			(size 0.4572 0.4572)
			(layers "F.Cu" "F.Mask" "F.Paste")
			(net "GND")
		)
		(pad "AG46" smd circle
			(at 19.949922 1.89992)
			(size 0.4572 0.4572)
			(layers "F.Cu" "F.Mask" "F.Paste")
			(net "Net_1393")
		)
		(pad "AG47" smd circle
			(at 20.899882 1.89992)
			(size 0.4572 0.4572)
			(layers "F.Cu" "F.Mask" "F.Paste")
			(net "Net_1473")
		)
		(pad "AG48" smd circle
			(at 21.850096 1.89992)
			(size 0.4572 0.4572)
			(layers "F.Cu" "F.Mask" "F.Paste")
			(net "GND")
		)
		(pad "AG49" smd circle
			(at 22.800056 1.89992)
			(size 0.4572 0.4572)
			(layers "F.Cu" "F.Mask" "F.Paste")
			(net "GND")
		)
		(pad "AH1" smd circle
			(at -22.800056 2.84988)
			(size 0.4572 0.4572)
			(layers "F.Cu" "F.Mask" "F.Paste")
			(net "GND")
		)
		(pad "AH2" smd circle
			(at -21.850096 2.84988)
			(size 0.4572 0.4572)
			(layers "F.Cu" "F.Mask" "F.Paste")
			(net "GND")
		)
		(pad "AH3" smd circle
			(at -20.899882 2.84988)
			(size 0.4572 0.4572)
			(layers "F.Cu" "F.Mask" "F.Paste")
			(net "GND")
		)
		(pad "AH4" smd circle
			(at -19.949922 2.84988)
			(size 0.4572 0.4572)
			(layers "F.Cu" "F.Mask" "F.Paste")
			(net "Net_5409")
		)
		(pad "AH5" smd circle
			(at -18.999962 2.84988)
			(size 0.4572 0.4572)
			(layers "F.Cu" "F.Mask" "F.Paste")
			(net "Net_5410")
		)
		(pad "AH6" smd circle
			(at -18.050002 2.84988)
			(size 0.4572 0.4572)
			(layers "F.Cu" "F.Mask" "F.Paste")
			(net "GND")
		)
		(pad "AH7" smd circle
			(at -17.100042 2.84988)
			(size 0.4572 0.4572)
			(layers "F.Cu" "F.Mask" "F.Paste")
			(net "SPI_PEX3_CLK")
		)
		(pad "AH8" smd circle
			(at -16.150082 2.84988)
			(size 0.4572 0.4572)
			(layers "F.Cu" "F.Mask" "F.Paste")
			(net "SPI_PEX3_SDIO3")
		)
		(pad "AH9" smd circle
			(at -15.200122 2.84988)
			(size 0.4572 0.4572)
			(layers "F.Cu" "F.Mask" "F.Paste")
			(net "GND")
		)
		(pad "AH10" smd circle
			(at -14.249908 2.84988)
			(size 0.4572 0.4572)
			(layers "F.Cu" "F.Mask" "F.Paste")
			(net "P1V8_PEX")
		)
		(pad "AH11" smd circle
			(at -13.299948 2.84988)
			(size 0.4572 0.4572)
			(layers "F.Cu" "F.Mask" "F.Paste")
			(net "GND")
		)
		(pad "AH12" smd circle
			(at -12.349988 2.84988)
			(size 0.4572 0.4572)
			(layers "F.Cu" "F.Mask" "F.Paste")
			(net "PCEPLL6_VDDA18_PEX3")
		)
		(pad "AH13" smd circle
			(at -11.400028 2.84988)
			(size 0.4572 0.4572)
			(layers "F.Cu" "F.Mask" "F.Paste")
			(net "GND")
		)
		(pad "AH14" smd circle
			(at -10.450068 2.84988)
			(size 0.4572 0.4572)
			(layers "F.Cu" "F.Mask" "F.Paste")
			(net "P0V8_PEX3")
		)
		(pad "AH15" smd circle
			(at -9.500108 2.84988)
			(size 0.4572 0.4572)
			(layers "F.Cu" "F.Mask" "F.Paste")
			(net "GND")
		)
		(pad "AH16" smd circle
			(at -8.549894 2.84988)
			(size 0.4572 0.4572)
			(layers "F.Cu" "F.Mask" "F.Paste")
			(net "P0V8_SERDES_VDDA_PEX3")
		)
		(pad "AH17" smd circle
			(at -7.599934 2.84988)
			(size 0.4572 0.4572)
			(layers "F.Cu" "F.Mask" "F.Paste")
			(net "P0V8_SERDES_VDDA_PEX3")
		)
		(pad "AH18" smd circle
			(at -6.649974 2.84988)
			(size 0.4572 0.4572)
			(layers "F.Cu" "F.Mask" "F.Paste")
			(net "P0V8_SERDES_VDDA_PEX3")
		)
		(pad "AH19" smd circle
			(at -5.700014 2.84988)
			(size 0.4572 0.4572)
			(layers "F.Cu" "F.Mask" "F.Paste")
			(net "P0V8_SERDES_VDDA_PEX3")
		)
		(pad "AH20" smd circle
			(at -4.750054 2.84988)
			(size 0.4572 0.4572)
			(layers "F.Cu" "F.Mask" "F.Paste")
			(net "P0V8_SERDES_VDDA_PEX3")
		)
		(pad "AH21" smd circle
			(at -3.800094 2.84988)
			(size 0.4572 0.4572)
			(layers "F.Cu" "F.Mask" "F.Paste")
			(net "P0V8_SERDES_VDDA_PEX3")
		)
		(pad "AH22" smd circle
			(at -2.84988 2.84988)
			(size 0.4572 0.4572)
			(layers "F.Cu" "F.Mask" "F.Paste")
			(net "P0V8_SERDES_VDDA_PEX3")
		)
		(pad "AH23" smd circle
			(at -1.89992 2.84988)
			(size 0.4572 0.4572)
			(layers "F.Cu" "F.Mask" "F.Paste")
			(net "P0V8_SERDES_VDDA_PEX3")
		)
		(pad "AH24" smd circle
			(at -0.94996 2.84988)
			(size 0.4572 0.4572)
			(layers "F.Cu" "F.Mask" "F.Paste")
			(net "P0V8_SERDES_VDDA_PEX3")
		)
		(pad "AH25" smd circle
			(at 0 2.84988)
			(size 0.4572 0.4572)
			(layers "F.Cu" "F.Mask" "F.Paste")
			(net "P0V8_SERDES_VDDA_PEX3")
		)
		(pad "AH26" smd circle
			(at 0.94996 2.84988)
			(size 0.4572 0.4572)
			(layers "F.Cu" "F.Mask" "F.Paste")
			(net "P0V8_SERDES_VDDA_PEX3")
		)
		(pad "AH27" smd circle
			(at 1.89992 2.84988)
			(size 0.4572 0.4572)
			(layers "F.Cu" "F.Mask" "F.Paste")
			(net "P0V8_SERDES_VDDA_PEX3")
		)
		(pad "AH28" smd circle
			(at 2.84988 2.84988)
			(size 0.4572 0.4572)
			(layers "F.Cu" "F.Mask" "F.Paste")
			(net "P0V8_SERDES_VDDA_PEX3")
		)
		(pad "AH29" smd circle
			(at 3.800094 2.84988)
			(size 0.4572 0.4572)
			(layers "F.Cu" "F.Mask" "F.Paste")
			(net "P0V8_SERDES_VDDA_PEX3")
		)
		(pad "AH30" smd circle
			(at 4.750054 2.84988)
			(size 0.4572 0.4572)
			(layers "F.Cu" "F.Mask" "F.Paste")
			(net "P0V8_SERDES_VDDA_PEX3")
		)
		(pad "AH31" smd circle
			(at 5.700014 2.84988)
			(size 0.4572 0.4572)
			(layers "F.Cu" "F.Mask" "F.Paste")
			(net "P0V8_SERDES_VDDA_PEX3")
		)
		(pad "AH32" smd circle
			(at 6.649974 2.84988)
			(size 0.4572 0.4572)
			(layers "F.Cu" "F.Mask" "F.Paste")
			(net "P0V8_SERDES_VDDA_PEX3")
		)
		(pad "AH33" smd circle
			(at 7.599934 2.84988)
			(size 0.4572 0.4572)
			(layers "F.Cu" "F.Mask" "F.Paste")
			(net "P0V8_SERDES_VDDA_PEX3")
		)
		(pad "AH34" smd circle
			(at 8.549894 2.84988)
			(size 0.4572 0.4572)
			(layers "F.Cu" "F.Mask" "F.Paste")
			(net "GND")
		)
		(pad "AH35" smd circle
			(at 9.500108 2.84988)
			(size 0.4572 0.4572)
			(layers "F.Cu" "F.Mask" "F.Paste")
			(net "GND")
		)
		(pad "AH36" smd circle
			(at 10.450068 2.84988)
			(size 0.4572 0.4572)
			(layers "F.Cu" "F.Mask" "F.Paste")
			(net "GND")
		)
		(pad "AH37" smd circle
			(at 11.400028 2.84988)
			(size 0.4572 0.4572)
			(layers "F.Cu" "F.Mask" "F.Paste")
			(net "GND")
		)
		(pad "AH38" smd circle
			(at 12.349988 2.84988)
			(size 0.4572 0.4572)
			(layers "F.Cu" "F.Mask" "F.Paste")
			(net "GND")
		)
		(pad "AH39" smd circle
			(at 13.299948 2.84988)
			(size 0.4572 0.4572)
			(layers "F.Cu" "F.Mask" "F.Paste")
			(net "GND")
		)
		(pad "AH40" smd circle
			(at 14.249908 2.84988)
			(size 0.4572 0.4572)
			(layers "F.Cu" "F.Mask" "F.Paste")
			(net "GND")
		)
		(pad "AH41" smd circle
			(at 15.200122 2.84988)
			(size 0.4572 0.4572)
			(layers "F.Cu" "F.Mask" "F.Paste")
			(net "Net_1537")
		)
		(pad "AH42" smd circle
			(at 16.150082 2.84988)
			(size 0.4572 0.4572)
			(layers "F.Cu" "F.Mask" "F.Paste")
			(net "Net_1544")
		)
		(pad "AH43" smd circle
			(at 17.100042 2.84988)
			(size 0.4572 0.4572)
			(layers "F.Cu" "F.Mask" "F.Paste")
			(net "GND")
		)
		(pad "AH44" smd circle
			(at 18.050002 2.84988)
			(size 0.4572 0.4572)
			(layers "F.Cu" "F.Mask" "F.Paste")
			(net "GND")
		)
		(pad "AH45" smd circle
			(at 18.999962 2.84988)
			(size 0.4572 0.4572)
			(layers "F.Cu" "F.Mask" "F.Paste")
			(net "GND")
		)
		(pad "AH46" smd circle
			(at 19.949922 2.84988)
			(size 0.4572 0.4572)
			(layers "F.Cu" "F.Mask" "F.Paste")
			(net "GND")
		)
		(pad "AH47" smd circle
			(at 20.899882 2.84988)
			(size 0.4572 0.4572)
			(layers "F.Cu" "F.Mask" "F.Paste")
			(net "GND")
		)
		(pad "AH48" smd circle
			(at 21.850096 2.84988)
			(size 0.4572 0.4572)
			(layers "F.Cu" "F.Mask" "F.Paste")
			(net "Net_1508")
		)
		(pad "AH49" smd circle
			(at 22.800056 2.84988)
			(size 0.4572 0.4572)
			(layers "F.Cu" "F.Mask" "F.Paste")
			(net "Net_1499")
		)
		(pad "AJ1" smd circle
			(at -22.800056 3.800094)
			(size 0.4572 0.4572)
			(layers "F.Cu" "F.Mask" "F.Paste")
			(net "Net_5412")
		)
		(pad "AJ2" smd circle
			(at -21.850096 3.800094)
			(size 0.4572 0.4572)
			(layers "F.Cu" "F.Mask" "F.Paste")
			(net "Net_5413")
		)
		(pad "AJ3" smd circle
			(at -20.899882 3.800094)
			(size 0.4572 0.4572)
			(layers "F.Cu" "F.Mask" "F.Paste")
			(net "GND")
		)
		(pad "AJ4" smd circle
			(at -19.949922 3.800094)
			(size 0.4572 0.4572)
			(layers "F.Cu" "F.Mask" "F.Paste")
			(net "GND")
		)
		(pad "AJ5" smd circle
			(at -18.999962 3.800094)
			(size 0.4572 0.4572)
			(layers "F.Cu" "F.Mask" "F.Paste")
			(net "GND")
		)
		(pad "AJ6" smd circle
			(at -18.050002 3.800094)
			(size 0.4572 0.4572)
			(layers "F.Cu" "F.Mask" "F.Paste")
			(net "GND")
		)
		(pad "AJ7" smd circle
			(at -17.100042 3.800094)
			(size 0.4572 0.4572)
			(layers "F.Cu" "F.Mask" "F.Paste")
			(net "SPI_PEX3_CS_N")
		)
		(pad "AJ8" smd circle
			(at -16.150082 3.800094)
			(size 0.4572 0.4572)
			(layers "F.Cu" "F.Mask" "F.Paste")
			(net "Net_5483")
		)
		(pad "AJ9" smd circle
			(at -15.200122 3.800094)
			(size 0.4572 0.4572)
			(layers "F.Cu" "F.Mask" "F.Paste")
			(net "GND")
		)
		(pad "AJ10" smd circle
			(at -14.249908 3.800094)
			(size 0.4572 0.4572)
			(layers "F.Cu" "F.Mask" "F.Paste")
			(net "P1V8_PEX")
		)
		(pad "AJ11" smd circle
			(at -13.299948 3.800094)
			(size 0.4572 0.4572)
			(layers "F.Cu" "F.Mask" "F.Paste")
			(net "GND")
		)
		(pad "AJ12" smd circle
			(at -12.349988 3.800094)
			(size 0.4572 0.4572)
			(layers "F.Cu" "F.Mask" "F.Paste")
			(net "GND")
		)
		(pad "AJ13" smd circle
			(at -11.400028 3.800094)
			(size 0.4572 0.4572)
			(layers "F.Cu" "F.Mask" "F.Paste")
			(net "PCEPLL7_VDDA18_PEX3")
		)
		(pad "AJ14" smd circle
			(at -10.450068 3.800094)
			(size 0.4572 0.4572)
			(layers "F.Cu" "F.Mask" "F.Paste")
			(net "GND")
		)
		(pad "AJ15" smd circle
			(at -9.500108 3.800094)
			(size 0.4572 0.4572)
			(layers "F.Cu" "F.Mask" "F.Paste")
			(net "P0V8_PEX3")
		)
		(pad "AJ16" smd circle
			(at -8.549894 3.800094)
			(size 0.4572 0.4572)
			(layers "F.Cu" "F.Mask" "F.Paste")
			(net "GND")
		)
		(pad "AJ17" smd circle
			(at -7.599934 3.800094)
			(size 0.4572 0.4572)
			(layers "F.Cu" "F.Mask" "F.Paste")
			(net "GND")
		)
		(pad "AJ18" smd circle
			(at -6.649974 3.800094)
			(size 0.4572 0.4572)
			(layers "F.Cu" "F.Mask" "F.Paste")
			(net "GND")
		)
		(pad "AJ19" smd circle
			(at -5.700014 3.800094)
			(size 0.4572 0.4572)
			(layers "F.Cu" "F.Mask" "F.Paste")
			(net "GND")
		)
		(pad "AJ20" smd circle
			(at -4.750054 3.800094)
			(size 0.4572 0.4572)
			(layers "F.Cu" "F.Mask" "F.Paste")
			(net "GND")
		)
		(pad "AJ21" smd circle
			(at -3.800094 3.800094)
			(size 0.4572 0.4572)
			(layers "F.Cu" "F.Mask" "F.Paste")
			(net "GND")
		)
		(pad "AJ22" smd circle
			(at -2.84988 3.800094)
			(size 0.4572 0.4572)
			(layers "F.Cu" "F.Mask" "F.Paste")
			(net "GND")
		)
		(pad "AJ23" smd circle
			(at -1.89992 3.800094)
			(size 0.4572 0.4572)
			(layers "F.Cu" "F.Mask" "F.Paste")
			(net "GND")
		)
		(pad "AJ24" smd circle
			(at -0.94996 3.800094)
			(size 0.4572 0.4572)
			(layers "F.Cu" "F.Mask" "F.Paste")
			(net "GND")
		)
		(pad "AJ25" smd circle
			(at 0 3.800094)
			(size 0.4572 0.4572)
			(layers "F.Cu" "F.Mask" "F.Paste")
			(net "GND")
		)
		(pad "AJ26" smd circle
			(at 0.94996 3.800094)
			(size 0.4572 0.4572)
			(layers "F.Cu" "F.Mask" "F.Paste")
			(net "GND")
		)
		(pad "AJ27" smd circle
			(at 1.89992 3.800094)
			(size 0.4572 0.4572)
			(layers "F.Cu" "F.Mask" "F.Paste")
			(net "GND")
		)
		(pad "AJ28" smd circle
			(at 2.84988 3.800094)
			(size 0.4572 0.4572)
			(layers "F.Cu" "F.Mask" "F.Paste")
			(net "GND")
		)
		(pad "AJ29" smd circle
			(at 3.800094 3.800094)
			(size 0.4572 0.4572)
			(layers "F.Cu" "F.Mask" "F.Paste")
			(net "GND")
		)
		(pad "AJ30" smd circle
			(at 4.750054 3.800094)
			(size 0.4572 0.4572)
			(layers "F.Cu" "F.Mask" "F.Paste")
			(net "GND")
		)
		(pad "AJ31" smd circle
			(at 5.700014 3.800094)
			(size 0.4572 0.4572)
			(layers "F.Cu" "F.Mask" "F.Paste")
			(net "GND")
		)
		(pad "AJ32" smd circle
			(at 6.649974 3.800094)
			(size 0.4572 0.4572)
			(layers "F.Cu" "F.Mask" "F.Paste")
			(net "GND")
		)
		(pad "AJ33" smd circle
			(at 7.599934 3.800094)
			(size 0.4572 0.4572)
			(layers "F.Cu" "F.Mask" "F.Paste")
			(net "GND")
		)
		(pad "AJ34" smd circle
			(at 8.549894 3.800094)
			(size 0.4572 0.4572)
			(layers "F.Cu" "F.Mask" "F.Paste")
			(net "GND")
		)
		(pad "AJ35" smd circle
			(at 9.500108 3.800094)
			(size 0.4572 0.4572)
			(layers "F.Cu" "F.Mask" "F.Paste")
			(net "GND")
		)
	)
)
